(kicad_pcb
	(version 20260206)
	(generator "pcbnew")
	(generator_version "10.0")
	(general
		(thickness 1.6)
		(legacy_teardrops no)
	)
	(paper "A4")
	(title_block
		(title "01162023_DA0F0TEBIF0_F0T_Expander_BD_F_brd_V02_OCP.brd")
		(comment 1 "Grand Teton / footprint 5622 of 9728 (PEX2), pads 475-594 of 2397")
	)
	(layers
		(0 "F.Cu" signal "TOP")
		(4 "In1.Cu" signal "GND")
		(6 "In2.Cu" signal "VCC")
		(8 "In3.Cu" signal "VCC1")
		(10 "In4.Cu" signal "GND1")
		(12 "In5.Cu" signal "IN1")
		(14 "In6.Cu" signal "GND2")
		(16 "In7.Cu" signal "IN2")
		(18 "In8.Cu" signal "GND3")
		(20 "In9.Cu" signal "IN3")
		(22 "In10.Cu" signal "GND4")
		(24 "In11.Cu" signal "IN4")
		(26 "In12.Cu" signal "GND5")
		(28 "In13.Cu" signal "IN5")
		(30 "In14.Cu" signal "GND6")
		(32 "In15.Cu" signal "IN6")
		(34 "In16.Cu" signal "GND7")
		(2 "B.Cu" signal "BOTTOM")
		(9 "F.Adhes" user "F.Adhesive")
		(11 "B.Adhes" user "B.Adhesive")
		(13 "F.Paste" user "Package Geometry/Pastemask Top")
		(15 "B.Paste" user "Package Geometry/Pastemask Bottom")
		(5 "F.SilkS" user "Ref Des/Silkscreen Top")
		(7 "B.SilkS" user "Ref Des/Silkscreen Bottom")
		(1 "F.Mask" user "Board Geometry/Soldermask Top")
		(3 "B.Mask" user "Board Geometry/Soldermask Bottom")
		(17 "Dwgs.User" user "User.Drawings")
		(19 "Cmts.User" user "User.Comments")
		(21 "Eco1.User" user "User.Eco1")
		(23 "Eco2.User" user "User.Eco2")
		(25 "Edge.Cuts" user "Board Geometry/Outline")
		(27 "Margin" user)
		(31 "F.CrtYd" user "Package Geometry/Place Bound Top")
		(29 "B.CrtYd" user "Package Geometry/Place Bound Bottom")
		(35 "F.Fab" user "Ref Des/Assembly Top")
		(33 "B.Fab" user "Ref Des/Assembly Bottom")
	)
	(footprint ""
		(layer "F.Cu")
		(at 291.84981 -295.89984)
		(property "Reference" "PEX2"
			(at -3.35153 35.56762 0)
			(unlocked yes)
			(layer "F.SilkS")
			(effects
				(font
					(size 2.032 1.524)
					(thickness 0.1524)
				)
				(justify left)
			)
		)
		(property "Value" ""
			(at 0 0 0)
			(layer "F.Fab")
			(effects
				(font
					(size 1.27 1.27)
				)
			)
		)
		(duplicate_pad_numbers_are_jumpers no)
		(pad "AJ36" smd circle
			(at 10.450068 3.800094)
			(size 0.4572 0.4572)
			(layers "F.Cu" "F.Mask" "F.Paste")
			(net "GND")
		)
		(pad "AJ37" smd circle
			(at 11.400028 3.800094)
			(size 0.4572 0.4572)
			(layers "F.Cu" "F.Mask" "F.Paste")
			(net "GND")
		)
		(pad "AJ38" smd circle
			(at 12.349988 3.800094)
			(size 0.4572 0.4572)
			(layers "F.Cu" "F.Mask" "F.Paste")
			(net "UART_PEX2_CLI_TX")
		)
		(pad "AJ39" smd circle
			(at 13.299948 3.800094)
			(size 0.4572 0.4572)
			(layers "F.Cu" "F.Mask" "F.Paste")
			(net "Net_5328")
		)
		(pad "AJ40" smd circle
			(at 14.249908 3.800094)
			(size 0.4572 0.4572)
			(layers "F.Cu" "F.Mask" "F.Paste")
			(net "GND")
		)
		(pad "AJ41" smd circle
			(at 15.200122 3.800094)
			(size 0.4572 0.4572)
			(layers "F.Cu" "F.Mask" "F.Paste")
			(net "GND")
		)
		(pad "AJ42" smd circle
			(at 16.150082 3.800094)
			(size 0.4572 0.4572)
			(layers "F.Cu" "F.Mask" "F.Paste")
			(net "GND")
		)
		(pad "AJ43" smd circle
			(at 17.100042 3.800094)
			(size 0.4572 0.4572)
			(layers "F.Cu" "F.Mask" "F.Paste")
			(net "Net_1703")
		)
		(pad "AJ44" smd circle
			(at 18.050002 3.800094)
			(size 0.4572 0.4572)
			(layers "F.Cu" "F.Mask" "F.Paste")
			(net "Net_1673")
		)
		(pad "AJ45" smd circle
			(at 18.999962 3.800094)
			(size 0.4572 0.4572)
			(layers "F.Cu" "F.Mask" "F.Paste")
			(net "GND")
		)
		(pad "AJ46" smd circle
			(at 19.949922 3.800094)
			(size 0.4572 0.4572)
			(layers "F.Cu" "F.Mask" "F.Paste")
			(net "Net_1632")
		)
		(pad "AJ47" smd circle
			(at 20.899882 3.800094)
			(size 0.4572 0.4572)
			(layers "F.Cu" "F.Mask" "F.Paste")
			(net "Net_1595")
		)
		(pad "AJ48" smd circle
			(at 21.850096 3.800094)
			(size 0.4572 0.4572)
			(layers "F.Cu" "F.Mask" "F.Paste")
			(net "GND")
		)
		(pad "AJ49" smd circle
			(at 22.800056 3.800094)
			(size 0.4572 0.4572)
			(layers "F.Cu" "F.Mask" "F.Paste")
			(net "GND")
		)
		(pad "AK1" smd circle
			(at -22.800056 4.750054)
			(size 0.4572 0.4572)
			(layers "F.Cu" "F.Mask" "F.Paste")
			(net "GND")
		)
		(pad "AK2" smd circle
			(at -21.850096 4.750054)
			(size 0.4572 0.4572)
			(layers "F.Cu" "F.Mask" "F.Paste")
			(net "GND")
		)
		(pad "AK3" smd circle
			(at -20.899882 4.750054)
			(size 0.4572 0.4572)
			(layers "F.Cu" "F.Mask" "F.Paste")
			(net "GND")
		)
		(pad "AK4" smd circle
			(at -19.949922 4.750054)
			(size 0.4572 0.4572)
			(layers "F.Cu" "F.Mask" "F.Paste")
			(net "Net_512")
		)
		(pad "AK5" smd circle
			(at -18.999962 4.750054)
			(size 0.4572 0.4572)
			(layers "F.Cu" "F.Mask" "F.Paste")
			(net "Net_511")
		)
		(pad "AK6" smd circle
			(at -18.050002 4.750054)
			(size 0.4572 0.4572)
			(layers "F.Cu" "F.Mask" "F.Paste")
			(net "GND")
		)
		(pad "AK7" smd circle
			(at -17.100042 4.750054)
			(size 0.4572 0.4572)
			(layers "F.Cu" "F.Mask" "F.Paste")
			(net "Net_5392")
		)
		(pad "AK8" smd circle
			(at -16.150082 4.750054)
			(size 0.4572 0.4572)
			(layers "F.Cu" "F.Mask" "F.Paste")
			(net "GND")
		)
		(pad "AK9" smd circle
			(at -15.200122 4.750054)
			(size 0.4572 0.4572)
			(layers "F.Cu" "F.Mask" "F.Paste")
			(net "GND")
		)
		(pad "AK10" smd circle
			(at -14.249908 4.750054)
			(size 0.4572 0.4572)
			(layers "F.Cu" "F.Mask" "F.Paste")
			(net "P1V8_PEX")
		)
		(pad "AK11" smd circle
			(at -13.299948 4.750054)
			(size 0.4572 0.4572)
			(layers "F.Cu" "F.Mask" "F.Paste")
			(net "GND")
		)
		(pad "AK12" smd circle
			(at -12.349988 4.750054)
			(size 0.4572 0.4572)
			(layers "F.Cu" "F.Mask" "F.Paste")
			(net "P1V8_PEX")
		)
		(pad "AK13" smd circle
			(at -11.400028 4.750054)
			(size 0.4572 0.4572)
			(layers "F.Cu" "F.Mask" "F.Paste")
			(net "GND")
		)
		(pad "AK14" smd circle
			(at -10.450068 4.750054)
			(size 0.4572 0.4572)
			(layers "F.Cu" "F.Mask" "F.Paste")
			(net "P0V8_PEX2")
		)
		(pad "AK15" smd circle
			(at -9.500108 4.750054)
			(size 0.4572 0.4572)
			(layers "F.Cu" "F.Mask" "F.Paste")
			(net "GND")
		)
		(pad "AK16" smd circle
			(at -8.549894 4.750054)
			(size 0.4572 0.4572)
			(layers "F.Cu" "F.Mask" "F.Paste")
			(net "P0V8_SERDES_VDDA_PEX2")
		)
		(pad "AK17" smd circle
			(at -7.599934 4.750054)
			(size 0.4572 0.4572)
			(layers "F.Cu" "F.Mask" "F.Paste")
			(net "P0V8_SERDES_VDDA_PEX2")
		)
		(pad "AK18" smd circle
			(at -6.649974 4.750054)
			(size 0.4572 0.4572)
			(layers "F.Cu" "F.Mask" "F.Paste")
			(net "P0V8_SERDES_VDDA_PEX2")
		)
		(pad "AK19" smd circle
			(at -5.700014 4.750054)
			(size 0.4572 0.4572)
			(layers "F.Cu" "F.Mask" "F.Paste")
			(net "P0V8_SERDES_VDDA_PEX2")
		)
		(pad "AK20" smd circle
			(at -4.750054 4.750054)
			(size 0.4572 0.4572)
			(layers "F.Cu" "F.Mask" "F.Paste")
			(net "P0V8_SERDES_VDDA_PEX2")
		)
		(pad "AK21" smd circle
			(at -3.800094 4.750054)
			(size 0.4572 0.4572)
			(layers "F.Cu" "F.Mask" "F.Paste")
			(net "P0V8_SERDES_VDDA_PEX2")
		)
		(pad "AK22" smd circle
			(at -2.84988 4.750054)
			(size 0.4572 0.4572)
			(layers "F.Cu" "F.Mask" "F.Paste")
			(net "P0V8_SERDES_VDDA_PEX2")
		)
		(pad "AK23" smd circle
			(at -1.89992 4.750054)
			(size 0.4572 0.4572)
			(layers "F.Cu" "F.Mask" "F.Paste")
			(net "P0V8_SERDES_VDDA_PEX2")
		)
		(pad "AK24" smd circle
			(at -0.94996 4.750054)
			(size 0.4572 0.4572)
			(layers "F.Cu" "F.Mask" "F.Paste")
			(net "P0V8_SERDES_VDDA_PEX2")
		)
		(pad "AK25" smd circle
			(at 0 4.750054)
			(size 0.4572 0.4572)
			(layers "F.Cu" "F.Mask" "F.Paste")
			(net "P0V8_SERDES_VDDA_PEX2")
		)
		(pad "AK26" smd circle
			(at 0.94996 4.750054)
			(size 0.4572 0.4572)
			(layers "F.Cu" "F.Mask" "F.Paste")
			(net "P0V8_SERDES_VDDA_PEX2")
		)
		(pad "AK27" smd circle
			(at 1.89992 4.750054)
			(size 0.4572 0.4572)
			(layers "F.Cu" "F.Mask" "F.Paste")
			(net "P0V8_SERDES_VDDA_PEX2")
		)
		(pad "AK28" smd circle
			(at 2.84988 4.750054)
			(size 0.4572 0.4572)
			(layers "F.Cu" "F.Mask" "F.Paste")
			(net "P0V8_SERDES_VDDA_PEX2")
		)
		(pad "AK29" smd circle
			(at 3.800094 4.750054)
			(size 0.4572 0.4572)
			(layers "F.Cu" "F.Mask" "F.Paste")
			(net "P0V8_SERDES_VDDA_PEX2")
		)
		(pad "AK30" smd circle
			(at 4.750054 4.750054)
			(size 0.4572 0.4572)
			(layers "F.Cu" "F.Mask" "F.Paste")
			(net "P0V8_SERDES_VDDA_PEX2")
		)
		(pad "AK31" smd circle
			(at 5.700014 4.750054)
			(size 0.4572 0.4572)
			(layers "F.Cu" "F.Mask" "F.Paste")
			(net "P0V8_SERDES_VDDA_PEX2")
		)
		(pad "AK32" smd circle
			(at 6.649974 4.750054)
			(size 0.4572 0.4572)
			(layers "F.Cu" "F.Mask" "F.Paste")
			(net "P0V8_SERDES_VDDA_PEX2")
		)
		(pad "AK33" smd circle
			(at 7.599934 4.750054)
			(size 0.4572 0.4572)
			(layers "F.Cu" "F.Mask" "F.Paste")
			(net "P0V8_SERDES_VDDA_PEX2")
		)
		(pad "AK34" smd circle
			(at 8.549894 4.750054)
			(size 0.4572 0.4572)
			(layers "F.Cu" "F.Mask" "F.Paste")
			(net "GND")
		)
		(pad "AK35" smd circle
			(at 9.500108 4.750054)
			(size 0.4572 0.4572)
			(layers "F.Cu" "F.Mask" "F.Paste")
			(net "P1V8_PEX")
		)
		(pad "AK36" smd circle
			(at 10.450068 4.750054)
			(size 0.4572 0.4572)
			(layers "F.Cu" "F.Mask" "F.Paste")
			(net "GND")
		)
		(pad "AK37" smd circle
			(at 11.400028 4.750054)
			(size 0.4572 0.4572)
			(layers "F.Cu" "F.Mask" "F.Paste")
			(net "GND")
		)
		(pad "AK38" smd circle
			(at 12.349988 4.750054)
			(size 0.4572 0.4572)
			(layers "F.Cu" "F.Mask" "F.Paste")
			(net "UART_PEX2_CLI_BUF_RX")
		)
		(pad "AK39" smd circle
			(at 13.299948 4.750054)
			(size 0.4572 0.4572)
			(layers "F.Cu" "F.Mask" "F.Paste")
			(net "UART_PEX2_SDB_BUF_RX")
		)
		(pad "AK40" smd circle
			(at 14.249908 4.750054)
			(size 0.4572 0.4572)
			(layers "F.Cu" "F.Mask" "F.Paste")
			(net "GND")
		)
		(pad "AK41" smd circle
			(at 15.200122 4.750054)
			(size 0.4572 0.4572)
			(layers "F.Cu" "F.Mask" "F.Paste")
			(net "Net_1693")
		)
		(pad "AK42" smd circle
			(at 16.150082 4.750054)
			(size 0.4572 0.4572)
			(layers "F.Cu" "F.Mask" "F.Paste")
			(net "Net_1677")
		)
		(pad "AK43" smd circle
			(at 17.100042 4.750054)
			(size 0.4572 0.4572)
			(layers "F.Cu" "F.Mask" "F.Paste")
			(net "GND")
		)
		(pad "AK44" smd circle
			(at 18.050002 4.750054)
			(size 0.4572 0.4572)
			(layers "F.Cu" "F.Mask" "F.Paste")
			(net "GND")
		)
		(pad "AK45" smd circle
			(at 18.999962 4.750054)
			(size 0.4572 0.4572)
			(layers "F.Cu" "F.Mask" "F.Paste")
			(net "GND")
		)
		(pad "AK46" smd circle
			(at 19.949922 4.750054)
			(size 0.4572 0.4572)
			(layers "F.Cu" "F.Mask" "F.Paste")
			(net "GND")
		)
		(pad "AK47" smd circle
			(at 20.899882 4.750054)
			(size 0.4572 0.4572)
			(layers "F.Cu" "F.Mask" "F.Paste")
			(net "GND")
		)
		(pad "AK48" smd circle
			(at 21.850096 4.750054)
			(size 0.4572 0.4572)
			(layers "F.Cu" "F.Mask" "F.Paste")
			(net "Net_1574")
		)
		(pad "AK49" smd circle
			(at 22.800056 4.750054)
			(size 0.4572 0.4572)
			(layers "F.Cu" "F.Mask" "F.Paste")
			(net "Net_1594")
		)
		(pad "AL1" smd circle
			(at -22.800056 5.700014)
			(size 0.4572 0.4572)
			(layers "F.Cu" "F.Mask" "F.Paste")
			(net "GND")
		)
		(pad "AL2" smd circle
			(at -21.850096 5.700014)
			(size 0.4572 0.4572)
			(layers "F.Cu" "F.Mask" "F.Paste")
			(net "GND")
		)
		(pad "AL3" smd circle
			(at -20.899882 5.700014)
			(size 0.4572 0.4572)
			(layers "F.Cu" "F.Mask" "F.Paste")
			(net "GND")
		)
		(pad "AL4" smd circle
			(at -19.949922 5.700014)
			(size 0.4572 0.4572)
			(layers "F.Cu" "F.Mask" "F.Paste")
			(net "GND")
		)
		(pad "AL5" smd circle
			(at -18.999962 5.700014)
			(size 0.4572 0.4572)
			(layers "F.Cu" "F.Mask" "F.Paste")
			(net "GND")
		)
		(pad "AL6" smd circle
			(at -18.050002 5.700014)
			(size 0.4572 0.4572)
			(layers "F.Cu" "F.Mask" "F.Paste")
			(net "GND")
		)
		(pad "AL7" smd circle
			(at -17.100042 5.700014)
			(size 0.4572 0.4572)
			(layers "F.Cu" "F.Mask" "F.Paste")
			(net "GND")
		)
		(pad "AL8" smd circle
			(at -16.150082 5.700014)
			(size 0.4572 0.4572)
			(layers "F.Cu" "F.Mask" "F.Paste")
			(net "GND")
		)
		(pad "AL9" smd circle
			(at -15.200122 5.700014)
			(size 0.4572 0.4572)
			(layers "F.Cu" "F.Mask" "F.Paste")
			(net "GND")
		)
		(pad "AL10" smd circle
			(at -14.249908 5.700014)
			(size 0.4572 0.4572)
			(layers "F.Cu" "F.Mask" "F.Paste")
			(net "GND")
		)
		(pad "AL11" smd circle
			(at -13.299948 5.700014)
			(size 0.4572 0.4572)
			(layers "F.Cu" "F.Mask" "F.Paste")
			(net "GND")
		)
		(pad "AL12" smd circle
			(at -12.349988 5.700014)
			(size 0.4572 0.4572)
			(layers "F.Cu" "F.Mask" "F.Paste")
			(net "GND")
		)
		(pad "AL13" smd circle
			(at -11.400028 5.700014)
			(size 0.4572 0.4572)
			(layers "F.Cu" "F.Mask" "F.Paste")
			(net "GND")
		)
		(pad "AL14" smd circle
			(at -10.450068 5.700014)
			(size 0.4572 0.4572)
			(layers "F.Cu" "F.Mask" "F.Paste")
			(net "VSSA_SENSE")
		)
		(pad "AL15" smd circle
			(at -9.500108 5.700014)
			(size 0.4572 0.4572)
			(layers "F.Cu" "F.Mask" "F.Paste")
			(net "VDDA_SENSE")
		)
		(pad "AL16" smd circle
			(at -8.549894 5.700014)
			(size 0.4572 0.4572)
			(layers "F.Cu" "F.Mask" "F.Paste")
			(net "GND")
		)
		(pad "AL17" smd circle
			(at -7.599934 5.700014)
			(size 0.4572 0.4572)
			(layers "F.Cu" "F.Mask" "F.Paste")
			(net "GND")
		)
		(pad "AL18" smd circle
			(at -6.649974 5.700014)
			(size 0.4572 0.4572)
			(layers "F.Cu" "F.Mask" "F.Paste")
			(net "GND")
		)
		(pad "AL19" smd circle
			(at -5.700014 5.700014)
			(size 0.4572 0.4572)
			(layers "F.Cu" "F.Mask" "F.Paste")
			(net "GND")
		)
		(pad "AL20" smd circle
			(at -4.750054 5.700014)
			(size 0.4572 0.4572)
			(layers "F.Cu" "F.Mask" "F.Paste")
			(net "GND")
		)
		(pad "AL21" smd circle
			(at -3.800094 5.700014)
			(size 0.4572 0.4572)
			(layers "F.Cu" "F.Mask" "F.Paste")
			(net "GND")
		)
		(pad "AL22" smd circle
			(at -2.84988 5.700014)
			(size 0.4572 0.4572)
			(layers "F.Cu" "F.Mask" "F.Paste")
			(net "GND")
		)
		(pad "AL23" smd circle
			(at -1.89992 5.700014)
			(size 0.4572 0.4572)
			(layers "F.Cu" "F.Mask" "F.Paste")
			(net "GND")
		)
		(pad "AL24" smd circle
			(at -0.94996 5.700014)
			(size 0.4572 0.4572)
			(layers "F.Cu" "F.Mask" "F.Paste")
			(net "GND")
		)
		(pad "AL25" smd circle
			(at 0 5.700014)
			(size 0.4572 0.4572)
			(layers "F.Cu" "F.Mask" "F.Paste")
			(net "GND")
		)
		(pad "AL26" smd circle
			(at 0.94996 5.700014)
			(size 0.4572 0.4572)
			(layers "F.Cu" "F.Mask" "F.Paste")
			(net "GND")
		)
		(pad "AL27" smd circle
			(at 1.89992 5.700014)
			(size 0.4572 0.4572)
			(layers "F.Cu" "F.Mask" "F.Paste")
			(net "GND")
		)
		(pad "AL28" smd circle
			(at 2.84988 5.700014)
			(size 0.4572 0.4572)
			(layers "F.Cu" "F.Mask" "F.Paste")
			(net "GND")
		)
		(pad "AL29" smd circle
			(at 3.800094 5.700014)
			(size 0.4572 0.4572)
			(layers "F.Cu" "F.Mask" "F.Paste")
			(net "GND")
		)
		(pad "AL30" smd circle
			(at 4.750054 5.700014)
			(size 0.4572 0.4572)
			(layers "F.Cu" "F.Mask" "F.Paste")
			(net "GND")
		)
		(pad "AL31" smd circle
			(at 5.700014 5.700014)
			(size 0.4572 0.4572)
			(layers "F.Cu" "F.Mask" "F.Paste")
			(net "GND")
		)
		(pad "AL32" smd circle
			(at 6.649974 5.700014)
			(size 0.4572 0.4572)
			(layers "F.Cu" "F.Mask" "F.Paste")
			(net "GND")
		)
		(pad "AL33" smd circle
			(at 7.599934 5.700014)
			(size 0.4572 0.4572)
			(layers "F.Cu" "F.Mask" "F.Paste")
			(net "GND")
		)
		(pad "AL34" smd circle
			(at 8.549894 5.700014)
			(size 0.4572 0.4572)
			(layers "F.Cu" "F.Mask" "F.Paste")
			(net "GND")
		)
		(pad "AL35" smd circle
			(at 9.500108 5.700014)
			(size 0.4572 0.4572)
			(layers "F.Cu" "F.Mask" "F.Paste")
			(net "P1V8_PEX")
		)
		(pad "AL36" smd circle
			(at 10.450068 5.700014)
			(size 0.4572 0.4572)
			(layers "F.Cu" "F.Mask" "F.Paste")
			(net "GND")
		)
		(pad "AL37" smd circle
			(at 11.400028 5.700014)
			(size 0.4572 0.4572)
			(layers "F.Cu" "F.Mask" "F.Paste")
			(net "GND")
		)
		(pad "AL38" smd circle
			(at 12.349988 5.700014)
			(size 0.4572 0.4572)
			(layers "F.Cu" "F.Mask" "F.Paste")
			(net "Net_5359")
		)
		(pad "AL39" smd circle
			(at 13.299948 5.700014)
			(size 0.4572 0.4572)
			(layers "F.Cu" "F.Mask" "F.Paste")
			(net "UART_PEX2_SDB_TX")
		)
		(pad "AL40" smd circle
			(at 14.249908 5.700014)
			(size 0.4572 0.4572)
			(layers "F.Cu" "F.Mask" "F.Paste")
			(net "GND")
		)
		(pad "AL41" smd circle
			(at 15.200122 5.700014)
			(size 0.4572 0.4572)
			(layers "F.Cu" "F.Mask" "F.Paste")
			(net "GND")
		)
		(pad "AL42" smd circle
			(at 16.150082 5.700014)
			(size 0.4572 0.4572)
			(layers "F.Cu" "F.Mask" "F.Paste")
			(net "GND")
		)
		(pad "AL43" smd circle
			(at 17.100042 5.700014)
			(size 0.4572 0.4572)
			(layers "F.Cu" "F.Mask" "F.Paste")
			(net "Net_1704")
		)
		(pad "AL44" smd circle
			(at 18.050002 5.700014)
			(size 0.4572 0.4572)
			(layers "F.Cu" "F.Mask" "F.Paste")
			(net "Net_1659")
		)
		(pad "AL45" smd circle
			(at 18.999962 5.700014)
			(size 0.4572 0.4572)
			(layers "F.Cu" "F.Mask" "F.Paste")
			(net "GND")
		)
		(pad "AL46" smd circle
			(at 19.949922 5.700014)
			(size 0.4572 0.4572)
			(layers "F.Cu" "F.Mask" "F.Paste")
			(net "Net_1607")
		)
		(pad "AL47" smd circle
			(at 20.899882 5.700014)
			(size 0.4572 0.4572)
			(layers "F.Cu" "F.Mask" "F.Paste")
			(net "Net_1601")
		)
		(pad "AL48" smd circle
			(at 21.850096 5.700014)
			(size 0.4572 0.4572)
			(layers "F.Cu" "F.Mask" "F.Paste")
			(net "GND")
		)
		(pad "AL49" smd circle
			(at 22.800056 5.700014)
			(size 0.4572 0.4572)
			(layers "F.Cu" "F.Mask" "F.Paste")
			(net "GND")
		)
		(pad "AM1" smd circle
			(at -22.800056 6.649974)
			(size 0.4572 0.4572)
			(layers "F.Cu" "F.Mask" "F.Paste")
			(net "Net_1590")
		)
		(pad "AM2" smd circle
			(at -21.850096 6.649974)
			(size 0.4572 0.4572)
			(layers "F.Cu" "F.Mask" "F.Paste")
			(net "Net_1565")
		)
		(pad "AM3" smd circle
			(at -20.899882 6.649974)
			(size 0.4572 0.4572)
			(layers "F.Cu" "F.Mask" "F.Paste")
			(net "GND")
		)
		(pad "AM4" smd circle
			(at -19.949922 6.649974)
			(size 0.4572 0.4572)
			(layers "F.Cu" "F.Mask" "F.Paste")
			(net "GND")
		)
		(pad "AM5" smd circle
			(at -18.999962 6.649974)
			(size 0.4572 0.4572)
			(layers "F.Cu" "F.Mask" "F.Paste")
			(net "GND")
		)
		(pad "AM6" smd circle
			(at -18.050002 6.649974)
			(size 0.4572 0.4572)
			(layers "F.Cu" "F.Mask" "F.Paste")
			(net "GND")
		)
		(pad "AM7" smd circle
			(at -17.100042 6.649974)
			(size 0.4572 0.4572)
			(layers "F.Cu" "F.Mask" "F.Paste")
			(net "GND")
		)
		(pad "AM8" smd circle
			(at -16.150082 6.649974)
			(size 0.4572 0.4572)
			(layers "F.Cu" "F.Mask" "F.Paste")
			(net "Net_1431")
		)
	)
)
